# BASEBOARD_FAB2 (Tioga Pass) — schematic netlist excerpt (pin names and nets, part order shuffled) for the footprints in the layout excerpt that follows; sources: Cadence DE-HDL packaged netlist, KiCad conversion of Wiwynn_Tioga_Pass_MB.brd

J8A1  CONN72_G97614002_A  CONN  pkg CP  page 173
  SIDEBANDA_7  = TP_FM_QAT_CBL_PRSNT0_R_N
  SIDEBANDA_0  = SGPIO_PCH_SATA_CLOCK_R
  GND(23)  = GND
  RXA1_DP  = SATA6G_P1_RX_C_DP
  RXA1_DN  = SATA6G_P1_RX_C_DN
  GND(22)  = GND
  RXA3_DP  = SATA6G_P3_RX_C_DP
  RXA3_DN  = SATA6G_P3_RX_C_DN
  GND(21)  = GND
  SIDEBANDA_3  = GND
  SIDEBANDA_1  = SGPIO_PCH_SATA_LOAD_R
  GND(20)  = GND
  RXA0_DP  = SATA6G_P0_RX_C_DP
  RXA0_DN  = SATA6G_P0_RX_C_DN
  GND(19)  = GND
  RXA2_DP  = SATA6G_P2_RX_C_DP
  RXA2_DN  = SATA6G_P2_RX_C_DN
  GND(18)  = GND
  SIDEBANDA_4  = SGPIO_PCH_SATA_DOUT0_R
  SIDEBANDA_2  = GND
  GND(17)  = GND
  TXA1_DP  = SATA6G_P1_TX_C_DP
  TXA1_DN  = SATA6G_P1_TX_C_DN
  GND(16)  = GND
  TXA3_DP  = SATA6G_P3_TX_C_DP
  TXA3_DN  = SATA6G_P3_TX_C_DN
  GND(15)  = GND
  SIDEBANDA_5  = PU_DATAIN1_SATA_0_R
  SIDEBANDA_6  = PD_SATA0_CONTROLLER_TYPE_R
  GND(14)  = GND
  TXA0_DP  = SATA6G_P0_TX_C_DP
  TXA0_DN  = SATA6G_P0_TX_C_DN
  GND(13)  = GND
  TXA2_DP  = SATA6G_P2_TX_C_DP
  TXA2_DN  = SATA6G_P2_TX_C_DN
  GND(12)  = GND
  SIDEBANDB_7  = TP_FM_QAT_CBL_PRSNT1_N_R
  SIDEBANDB_0  = TP_SGPIO_SATA_CLOCK1_R
  GND(11)  = GND
  RXB1_DP  = SATA6G_P5_RX_C_DP
  RXB1_DN  = SATA6G_P5_RX_C_DN
  GND(10)  = GND
  RXB3_DP  = SATA6G_P7_RX_C_DP
  RXB3_DN  = SATA6G_P7_RX_C_DN
  GND(9)  = GND
  SIDEBANDB_3  = GND
  SIDEBANDB_1  = TP_SGPIO_SATA_LOAD1_R
  GND(8)  = GND
  RXB0_DP  = SATA6G_P4_RX_C_DP
  RXB0_DN  = SATA6G_P4_RX_C_DN
  GND(7)  = GND
  RXB2_DP  = SATA6G_P6_RX_C_DP
  RXB2_DN  = SATA6G_P6_RX_C_DN
  GND(6)  = GND
  SIDEBANDB_4  = TP_SGPIO_SATA_DATA1_R
  SIDEBANDB_2  = GND
  GND(5)  = GND
  TXB1_DP  = SATA6G_P5_TX_C_DP
  TXB1_DN  = SATA6G_P5_TX_C_DN
  GND(4)  = GND
  TXB3_DP  = SATA6G_P7_TX_C_DP
  TXB3_DN  = SATA6G_P7_TX_C_DN
  GND(3)  = GND
  SIDEBANDB_5  = PU_DATAIN1_SATA_1_R
  SIDEBANDB_6  = PD_SATA1_CONTROLLER_TYPE_R
  GND(2)  = GND
  TXB0_DP  = SATA6G_P4_TX_C_DP
  TXB0_DN  = SATA6G_P4_TX_C_DN
  GND(1)  = GND
  TXB2_DP  = SATA6G_P6_TX_C_DP
  TXB2_DN  = SATA6G_P6_TX_C_DN
  GND(0)  = GND

(kicad_pcb
	(version 20260206)
	(generator "pcbnew")
	(generator_version "10.0")
	(general
		(thickness 1.6)
		(legacy_teardrops no)
	)
	(paper "A4")
	(title_block
		(title "Wiwynn_Tioga_Pass_MB.brd")
		(comment 1 "Tioga Pass / footprint 1251 of 4770 (J8A1), pads 32-62 of 77")
	)
	(layers
		(0 "F.Cu" signal "TOP")
		(4 "In1.Cu" signal "L2GND")
		(6 "In2.Cu" signal "L3")
		(8 "In3.Cu" signal "L4GND")
		(10 "In4.Cu" signal "L5")
		(12 "In5.Cu" signal "L6GND")
		(14 "In6.Cu" signal "L7VCC")
		(16 "In7.Cu" signal "L8VCC")
		(18 "In8.Cu" signal "L9GND")
		(20 "In9.Cu" signal "L10")
		(22 "In10.Cu" signal "L11GND")
		(24 "In11.Cu" signal "L12")
		(26 "In12.Cu" signal "L13GND")
		(2 "B.Cu" signal "BOTTOM")
		(9 "F.Adhes" user "F.Adhesive")
		(11 "B.Adhes" user "B.Adhesive")
		(13 "F.Paste" user "Package Geometry/Pastemask Top")
		(15 "B.Paste" user "Package Geometry/Pastemask Bottom")
		(5 "F.SilkS" user "Ref Des/Silkscreen Top")
		(7 "B.SilkS" user "Ref Des/Silkscreen Bottom")
		(1 "F.Mask" user "Board Geometry/Soldermask Top")
		(3 "B.Mask" user "Board Geometry/Soldermask Bottom")
		(17 "Dwgs.User" user "User.Drawings")
		(19 "Cmts.User" user "User.Comments")
		(21 "Eco1.User" user "User.Eco1")
		(23 "Eco2.User" user "User.Eco2")
		(25 "Edge.Cuts" user "Board Geometry/Outline")
		(27 "Margin" user)
		(31 "F.CrtYd" user "Package Geometry/Place Bound Top")
		(29 "B.CrtYd" user "Package Geometry/Place Bound Bottom")
		(35 "F.Fab" user "Ref Des/Assembly Top")
		(33 "B.Fab" user "Ref Des/Assembly Bottom")
	)
	(footprint ""
		(layer "F.Cu")
		(at 430.276 -154.94 -90)
		(property "Reference" "J8A1"
			(at 15.64767 10.287 0)
			(unlocked yes)
			(layer "B.SilkS")
			(effects
				(font
					(size 0.7874 0.5842)
					(thickness 0.1524)
				)
				(justify left mirror)
			)
		)
		(property "Value" ""
			(at 0 0 270)
			(layer "F.Fab")
			(effects
				(font
					(size 1.27 1.27)
				)
			)
		)
		(duplicate_pad_numbers_are_jumpers no)
		(pad "1C9" thru_hole circle
			(at 6.89991 5.999988 270)
			(size 0.7874 0.7874)
			(drill 0.381)
			(layers "*.Cu" "*.Mask")
			(remove_unused_layers no)
			(net "GND")
			(clearance 0.1143)
			(thermal_gap 0.1143)
		)
		(pad "1D1" thru_hole circle
			(at 11.400028 0 270)
			(size 0.7874 0.7874)
			(drill 0.381)
			(layers "*.Cu" "*.Mask")
			(remove_unused_layers no)
			(net "PU_DATAIN1_SATA_0_R")
			(clearance 0.1143)
			(thermal_gap 0.1143)
		)
		(pad "1D2" thru_hole circle
			(at 9.99998 0.750062 270)
			(size 0.7874 0.7874)
			(drill 0.381)
			(layers "*.Cu" "*.Mask")
			(remove_unused_layers no)
			(net "PD_SATA0_CONTROLLER_TYPE_R")
			(clearance 0.1143)
			(thermal_gap 0.1143)
		)
		(pad "1D3" thru_hole circle
			(at 10.700004 1.500124 270)
			(size 0.7874 0.7874)
			(drill 0.381)
			(layers "*.Cu" "*.Mask")
			(remove_unused_layers no)
			(net "GND")
			(clearance 0.1143)
			(thermal_gap 0.1143)
		)
		(pad "1D4" thru_hole circle
			(at 11.400028 2.249932 270)
			(size 0.7874 0.7874)
			(drill 0.381)
			(layers "*.Cu" "*.Mask")
			(remove_unused_layers no)
			(net "SATA6G_P0_TX_C_DP")
			(clearance 0.1143)
			(thermal_gap 0.1143)
		)
		(pad "1D5" thru_hole circle
			(at 9.99998 2.999994 270)
			(size 0.7874 0.7874)
			(drill 0.381)
			(layers "*.Cu" "*.Mask")
			(remove_unused_layers no)
			(net "SATA6G_P0_TX_C_DN")
			(clearance 0.1143)
			(thermal_gap 0.1143)
		)
		(pad "1D6" thru_hole circle
			(at 10.700004 3.750056 270)
			(size 0.7874 0.7874)
			(drill 0.381)
			(layers "*.Cu" "*.Mask")
			(remove_unused_layers no)
			(net "GND")
			(clearance 0.1143)
			(thermal_gap 0.1143)
		)
		(pad "1D7" thru_hole circle
			(at 11.400028 4.500118 270)
			(size 0.7874 0.7874)
			(drill 0.381)
			(layers "*.Cu" "*.Mask")
			(remove_unused_layers no)
			(net "SATA6G_P2_TX_C_DP")
			(clearance 0.1143)
			(thermal_gap 0.1143)
		)
		(pad "1D8" thru_hole circle
			(at 9.99998 5.249926 270)
			(size 0.7874 0.7874)
			(drill 0.381)
			(layers "*.Cu" "*.Mask")
			(remove_unused_layers no)
			(net "SATA6G_P2_TX_C_DN")
			(clearance 0.1143)
			(thermal_gap 0.1143)
		)
		(pad "1D9" thru_hole circle
			(at 10.700004 5.999988 270)
			(size 0.7874 0.7874)
			(drill 0.381)
			(layers "*.Cu" "*.Mask")
			(remove_unused_layers no)
			(net "GND")
			(clearance 0.1143)
			(thermal_gap 0.1143)
		)
		(pad "2A1" thru_hole circle
			(at 0 11.999976 270)
			(size 0.7874 0.7874)
			(drill 0.381)
			(layers "*.Cu" "*.Mask")
			(remove_unused_layers no)
			(net "TP_FM_QAT_CBL_PRSNT1_N_R")
			(clearance 0.1143)
			(thermal_gap 0.1143)
		)
		(pad "2A2" thru_hole circle
			(at -1.400048 12.750038 270)
			(size 0.7874 0.7874)
			(drill 0.381)
			(layers "*.Cu" "*.Mask")
			(remove_unused_layers no)
			(net "TP_SGPIO_SATA_CLOCK1_R")
			(clearance 0.1143)
			(thermal_gap 0.1143)
		)
		(pad "2A3" thru_hole circle
			(at -0.700024 13.5001 270)
			(size 0.7874 0.7874)
			(drill 0.381)
			(layers "*.Cu" "*.Mask")
			(remove_unused_layers no)
			(net "GND")
			(clearance 0.1143)
			(thermal_gap 0.1143)
		)
		(pad "2A4" thru_hole circle
			(at 0 14.249908 270)
			(size 0.7874 0.7874)
			(drill 0.381)
			(layers "*.Cu" "*.Mask")
			(remove_unused_layers no)
			(net "SATA6G_P5_RX_C_DP")
			(clearance 0.1143)
			(thermal_gap 0.1143)
		)
		(pad "2A5" thru_hole circle
			(at -1.400048 14.99997 270)
			(size 0.7874 0.7874)
			(drill 0.381)
			(layers "*.Cu" "*.Mask")
			(remove_unused_layers no)
			(net "SATA6G_P5_RX_C_DN")
			(clearance 0.1143)
			(thermal_gap 0.1143)
		)
		(pad "2A6" thru_hole circle
			(at -0.700024 15.750032 270)
			(size 0.7874 0.7874)
			(drill 0.381)
			(layers "*.Cu" "*.Mask")
			(remove_unused_layers no)
			(net "GND")
			(clearance 0.1143)
			(thermal_gap 0.1143)
		)
		(pad "2A7" thru_hole circle
			(at 0 16.500094 270)
			(size 0.7874 0.7874)
			(drill 0.381)
			(layers "*.Cu" "*.Mask")
			(remove_unused_layers no)
			(net "SATA6G_P7_RX_C_DP")
			(clearance 0.1143)
			(thermal_gap 0.1143)
		)
		(pad "2A8" thru_hole circle
			(at -1.400048 17.249902 270)
			(size 0.7874 0.7874)
			(drill 0.381)
			(layers "*.Cu" "*.Mask")
			(remove_unused_layers no)
			(net "SATA6G_P7_RX_C_DN")
			(clearance 0.1143)
			(thermal_gap 0.1143)
		)
		(pad "2A9" thru_hole circle
			(at -0.700024 17.999964 270)
			(size 0.7874 0.7874)
			(drill 0.381)
			(layers "*.Cu" "*.Mask")
			(remove_unused_layers no)
			(net "GND")
			(clearance 0.1143)
			(thermal_gap 0.1143)
		)
		(pad "2B1" thru_hole circle
			(at 3.800094 11.999976 270)
			(size 0.7874 0.7874)
			(drill 0.381)
			(layers "*.Cu" "*.Mask")
			(remove_unused_layers no)
			(net "GND")
			(clearance 0.1143)
			(thermal_gap 0.1143)
		)
		(pad "2B2" thru_hole circle
			(at 2.400046 12.750038 270)
			(size 0.7874 0.7874)
			(drill 0.381)
			(layers "*.Cu" "*.Mask")
			(remove_unused_layers no)
			(net "TP_SGPIO_SATA_LOAD1_R")
			(clearance 0.1143)
			(thermal_gap 0.1143)
		)
		(pad "2B3" thru_hole circle
			(at 3.10007 13.5001 270)
			(size 0.7874 0.7874)
			(drill 0.381)
			(layers "*.Cu" "*.Mask")
			(remove_unused_layers no)
			(net "GND")
			(clearance 0.1143)
			(thermal_gap 0.1143)
		)
		(pad "2B4" thru_hole circle
			(at 3.800094 14.249908 270)
			(size 0.7874 0.7874)
			(drill 0.381)
			(layers "*.Cu" "*.Mask")
			(remove_unused_layers no)
			(net "SATA6G_P4_RX_C_DP")
			(clearance 0.1143)
			(thermal_gap 0.1143)
		)
		(pad "2B5" thru_hole circle
			(at 2.400046 14.99997 270)
			(size 0.7874 0.7874)
			(drill 0.381)
			(layers "*.Cu" "*.Mask")
			(remove_unused_layers no)
			(net "SATA6G_P4_RX_C_DN")
			(clearance 0.1143)
			(thermal_gap 0.1143)
		)
		(pad "2B6" thru_hole circle
			(at 3.10007 15.750032 270)
			(size 0.7874 0.7874)
			(drill 0.381)
			(layers "*.Cu" "*.Mask")
			(remove_unused_layers no)
			(net "GND")
			(clearance 0.1143)
			(thermal_gap 0.1143)
		)
		(pad "2B7" thru_hole circle
			(at 3.800094 16.500094 270)
			(size 0.7874 0.7874)
			(drill 0.381)
			(layers "*.Cu" "*.Mask")
			(remove_unused_layers no)
			(net "SATA6G_P6_RX_C_DP")
			(clearance 0.1143)
			(thermal_gap 0.1143)
		)
		(pad "2B8" thru_hole circle
			(at 2.400046 17.249902 270)
			(size 0.7874 0.7874)
			(drill 0.381)
			(layers "*.Cu" "*.Mask")
			(remove_unused_layers no)
			(net "SATA6G_P6_RX_C_DN")
			(clearance 0.1143)
			(thermal_gap 0.1143)
		)
		(pad "2B9" thru_hole circle
			(at 3.10007 17.999964 270)
			(size 0.7874 0.7874)
			(drill 0.381)
			(layers "*.Cu" "*.Mask")
			(remove_unused_layers no)
			(net "GND")
			(clearance 0.1143)
			(thermal_gap 0.1143)
		)
		(pad "2C1" thru_hole circle
			(at 7.599934 11.999976 270)
			(size 0.7874 0.7874)
			(drill 0.381)
			(layers "*.Cu" "*.Mask")
			(remove_unused_layers no)
			(net "TP_SGPIO_SATA_DATA1_R")
			(clearance 0.1143)
			(thermal_gap 0.1143)
		)
		(pad "2C2" thru_hole circle
			(at 6.199886 12.750038 270)
			(size 0.7874 0.7874)
			(drill 0.381)
			(layers "*.Cu" "*.Mask")
			(remove_unused_layers no)
			(net "GND")
			(clearance 0.1143)
			(thermal_gap 0.1143)
		)
		(pad "2C3" thru_hole circle
			(at 6.89991 13.5001 270)
			(size 0.7874 0.7874)
			(drill 0.381)
			(layers "*.Cu" "*.Mask")
			(remove_unused_layers no)
			(net "GND")
			(clearance 0.1143)
			(thermal_gap 0.1143)
		)
	)
)
